# S9S_MB_2U (Grand Teton) — schematic netlist excerpt (pin names and nets, part order shuffled) for the footprints in the layout excerpt that follows; sources: Cadence DE-HDL packaged netlist, KiCad conversion of 03242023_DA0F0TMBIJ0_F0T_Motherboard_J_brd_V01_OCP.brd

R1007  Q_RES  4.7K 5% CHIP  pkg 0402LF  page 235 : A = PVNN_TERM_CPU1 ; B = FM_PEHPCPU1_ALERT_N
R3904  Q_RES  49.9 1% CHIP  pkg 0402LF  page 111 : A = I3C_SPD_DDREFGH_CPU1_LVC1_SCL_5 ; B = I3C_SPD_DDREFGH_CPU1_LVC1_SCL

(kicad_pcb
	(version 20260206)
	(generator "pcbnew")
	(generator_version "10.0")
	(general
		(thickness 1.6)
		(legacy_teardrops no)
	)
	(paper "A4")
	(title_block
		(title "03242023_DA0F0TMBIJ0_F0T_Motherboard_J_brd_V01_OCP.brd")
		(comment 1 "Grand Teton / footprints 5412-5413 of 6105")
	)
	(layers
		(0 "F.Cu" signal "TOP")
		(4 "In1.Cu" signal "GND")
		(6 "In2.Cu" signal "IN1")
		(8 "In3.Cu" signal "GND1")
		(10 "In4.Cu" signal "IN2")
		(12 "In5.Cu" signal "GND2")
		(14 "In6.Cu" signal "IN3")
		(16 "In7.Cu" signal "GND3")
		(18 "In8.Cu" signal "VCC")
		(20 "In9.Cu" signal "VCC1")
		(22 "In10.Cu" signal "GND4")
		(24 "In11.Cu" signal "IN4")
		(26 "In12.Cu" signal "GND5")
		(28 "In13.Cu" signal "IN5")
		(30 "In14.Cu" signal "GND6")
		(32 "In15.Cu" signal "IN6")
		(34 "In16.Cu" signal "GND7")
		(2 "B.Cu" signal "BOTTOM")
		(9 "F.Adhes" user "F.Adhesive")
		(11 "B.Adhes" user "B.Adhesive")
		(13 "F.Paste" user "Package Geometry/Pastemask Top")
		(15 "B.Paste" user "Package Geometry/Pastemask Bottom")
		(5 "F.SilkS" user "Ref Des/Silkscreen Top")
		(7 "B.SilkS" user "Ref Des/Silkscreen Bottom")
		(1 "F.Mask" user "Board Geometry/Soldermask Top")
		(3 "B.Mask" user "Board Geometry/Soldermask Bottom")
		(17 "Dwgs.User" user "User.Drawings")
		(19 "Cmts.User" user "User.Comments")
		(21 "Eco1.User" user "User.Eco1")
		(23 "Eco2.User" user "User.Eco2")
		(25 "Edge.Cuts" user "Board Geometry/Outline")
		(27 "Margin" user)
		(31 "F.CrtYd" user "Package Geometry/Place Bound Top")
		(29 "B.CrtYd" user "Package Geometry/Place Bound Bottom")
		(35 "F.Fab" user "Ref Des/Assembly Top")
		(33 "B.Fab" user "Ref Des/Assembly Bottom")
	)
	(footprint ""
		(layer "B.Cu")
		(at 188.981588 -316.866778 90)
		(property "Reference" "R3904"
			(at 0 0 90)
			(layer "B.SilkS")
			(hide yes)
			(effects
				(font
					(size 1.27 1.27)
				)
				(justify mirror)
			)
		)
		(property "Value" ""
			(at 0 0 90)
			(layer "B.Fab")
			(effects
				(font
					(size 1.27 1.27)
				)
				(justify mirror)
			)
		)
		(duplicate_pad_numbers_are_jumpers no)
		(fp_line
			(start 0.7874 -0.4064)
			(end -0.7874 -0.4064)
			(stroke
				(width 0.1524)
				(type default)
			)
			(layer "B.SilkS")
		)
		(fp_line
			(start -0.7874 -0.4064)
			(end -0.7874 0.4064)
			(stroke
				(width 0.1524)
				(type default)
			)
			(layer "B.SilkS")
		)
		(fp_line
			(start 0.7874 0.4064)
			(end 0.7874 -0.4064)
			(stroke
				(width 0.1524)
				(type default)
			)
			(layer "B.SilkS")
		)
		(fp_line
			(start -0.7874 0.4064)
			(end 0.7874 0.4064)
			(stroke
				(width 0.1524)
				(type default)
			)
			(layer "B.SilkS")
		)
		(fp_line
			(start 0.67945 -0.305054)
			(end 0.12065 -0.305054)
			(stroke
				(width 0.1)
				(type default)
			)
			(layer "B.Fab")
		)
		(fp_line
			(start 0.12065 -0.305054)
			(end 0.12065 -0.2794)
			(stroke
				(width 0.1)
				(type default)
			)
			(layer "B.Fab")
		)
		(fp_line
			(start -0.12065 -0.3048)
			(end -0.67945 -0.3048)
			(stroke
				(width 0.1)
				(type default)
			)
			(layer "B.Fab")
		)
		(fp_line
			(start -0.67945 -0.3048)
			(end -0.67945 0.3048)
			(stroke
				(width 0.1)
				(type default)
			)
			(layer "B.Fab")
		)
		(fp_line
			(start 0.12065 -0.2794)
			(end -0.12065 -0.2794)
			(stroke
				(width 0.1)
				(type default)
			)
			(layer "B.Fab")
		)
		(fp_line
			(start -0.12065 -0.2794)
			(end -0.12065 -0.3048)
			(stroke
				(width 0.1)
				(type default)
			)
			(layer "B.Fab")
		)
		(fp_line
			(start 0.12065 0.2794)
			(end 0.12065 0.3048)
			(stroke
				(width 0.1)
				(type default)
			)
			(layer "B.Fab")
		)
		(fp_line
			(start -0.120396 0.2794)
			(end 0.12065 0.2794)
			(stroke
				(width 0.1)
				(type default)
			)
			(layer "B.Fab")
		)
		(fp_line
			(start 0.67945 0.3048)
			(end 0.67945 -0.305054)
			(stroke
				(width 0.1)
				(type default)
			)
			(layer "B.Fab")
		)
		(fp_line
			(start 0.12065 0.3048)
			(end 0.67945 0.3048)
			(stroke
				(width 0.1)
				(type default)
			)
			(layer "B.Fab")
		)
		(fp_line
			(start -0.120396 0.3048)
			(end -0.120396 0.2794)
			(stroke
				(width 0.1)
				(type default)
			)
			(layer "B.Fab")
		)
		(fp_line
			(start -0.67945 0.3048)
			(end -0.120396 0.3048)
			(stroke
				(width 0.1)
				(type default)
			)
			(layer "B.Fab")
		)
		(pad "1" smd circle
			(at 0.40005 0 270)
			(size 0 0)
			(layers "B.Cu" "B.Mask" "B.Paste")
			(net "I3C_SPD_DDREFGH_CPU1_LVC1_SCL_5")
		)
		(pad "2" smd circle
			(at -0.40005 0 270)
			(size 0 0)
			(layers "B.Cu" "B.Mask" "B.Paste")
			(net "I3C_SPD_DDREFGH_CPU1_LVC1_SCL")
		)
	)
	(footprint ""
		(layer "B.Cu")
		(at 90.410284 -184.01665 90)
		(property "Reference" "R1007"
			(at 0 0 90)
			(layer "B.SilkS")
			(hide yes)
			(effects
				(font
					(size 1.27 1.27)
				)
				(justify mirror)
			)
		)
		(property "Value" ""
			(at 0 0 90)
			(layer "B.Fab")
			(effects
				(font
					(size 1.27 1.27)
				)
				(justify mirror)
			)
		)
		(duplicate_pad_numbers_are_jumpers no)
		(fp_line
			(start 0.7874 -0.4064)
			(end -0.7874 -0.4064)
			(stroke
				(width 0.1524)
				(type default)
			)
			(layer "B.SilkS")
		)
		(fp_line
			(start -0.7874 -0.4064)
			(end -0.7874 0.4064)
			(stroke
				(width 0.1524)
				(type default)
			)
			(layer "B.SilkS")
		)
		(fp_line
			(start 0.7874 0.4064)
			(end 0.7874 -0.4064)
			(stroke
				(width 0.1524)
				(type default)
			)
			(layer "B.SilkS")
		)
		(fp_line
			(start -0.7874 0.4064)
			(end 0.7874 0.4064)
			(stroke
				(width 0.1524)
				(type default)
			)
			(layer "B.SilkS")
		)
		(fp_line
			(start 0.67945 -0.305054)
			(end 0.12065 -0.305054)
			(stroke
				(width 0.1)
				(type default)
			)
			(layer "B.Fab")
		)
		(fp_line
			(start 0.12065 -0.305054)
			(end 0.12065 -0.2794)
			(stroke
				(width 0.1)
				(type default)
			)
			(layer "B.Fab")
		)
		(fp_line
			(start -0.12065 -0.3048)
			(end -0.67945 -0.3048)
			(stroke
				(width 0.1)
				(type default)
			)
			(layer "B.Fab")
		)
		(fp_line
			(start -0.67945 -0.3048)
			(end -0.67945 0.3048)
			(stroke
				(width 0.1)
				(type default)
			)
			(layer "B.Fab")
		)
		(fp_line
			(start 0.12065 -0.2794)
			(end -0.12065 -0.2794)
			(stroke
				(width 0.1)
				(type default)
			)
			(layer "B.Fab")
		)
		(fp_line
			(start -0.12065 -0.2794)
			(end -0.12065 -0.3048)
			(stroke
				(width 0.1)
				(type default)
			)
			(layer "B.Fab")
		)
		(fp_line
			(start 0.12065 0.2794)
			(end 0.12065 0.3048)
			(stroke
				(width 0.1)
				(type default)
			)
			(layer "B.Fab")
		)
		(fp_line
			(start -0.120396 0.2794)
			(end 0.12065 0.2794)
			(stroke
				(width 0.1)
				(type default)
			)
			(layer "B.Fab")
		)
		(fp_line
			(start 0.67945 0.3048)
			(end 0.67945 -0.305054)
			(stroke
				(width 0.1)
				(type default)
			)
			(layer "B.Fab")
		)
		(fp_line
			(start 0.12065 0.3048)
			(end 0.67945 0.3048)
			(stroke
				(width 0.1)
				(type default)
			)
			(layer "B.Fab")
		)
		(fp_line
			(start -0.120396 0.3048)
			(end -0.120396 0.2794)
			(stroke
				(width 0.1)
				(type default)
			)
			(layer "B.Fab")
		)
		(fp_line
			(start -0.67945 0.3048)
			(end -0.120396 0.3048)
			(stroke
				(width 0.1)
				(type default)
			)
			(layer "B.Fab")
		)
		(pad "1" smd circle
			(at 0.40005 0 270)
			(size 0 0)
			(layers "B.Cu" "B.Mask" "B.Paste")
			(net "PVNN_TERM_CPU1")
		)
		(pad "2" smd circle
			(at -0.40005 0 270)
			(size 0 0)
			(layers "B.Cu" "B.Mask" "B.Paste")
			(net "FM_PEHPCPU1_ALERT_N")
		)
	)
)
